(kicad_pcb
	(version 20260206)
	(generator "pcbnew")
	(generator_version "10.0")
	(general
		(thickness 1.6)
		(legacy_teardrops no)
	)
	(paper "A4")
	(title_block
		(title "Wiwynn_Tioga_Pass_MB.brd")
		(comment 1 "Tioga Pass / footprints 3305-3311 of 4770")
	)
	(layers
		(0 "F.Cu" signal "TOP")
		(4 "In1.Cu" signal "L2GND")
		(6 "In2.Cu" signal "L3")
		(8 "In3.Cu" signal "L4GND")
		(10 "In4.Cu" signal "L5")
		(12 "In5.Cu" signal "L6GND")
		(14 "In6.Cu" signal "L7VCC")
		(16 "In7.Cu" signal "L8VCC")
		(18 "In8.Cu" signal "L9GND")
		(20 "In9.Cu" signal "L10")
		(22 "In10.Cu" signal "L11GND")
		(24 "In11.Cu" signal "L12")
		(26 "In12.Cu" signal "L13GND")
		(2 "B.Cu" signal "BOTTOM")
		(9 "F.Adhes" user "F.Adhesive")
		(11 "B.Adhes" user "B.Adhesive")
		(13 "F.Paste" user "Package Geometry/Pastemask Top")
		(15 "B.Paste" user "Package Geometry/Pastemask Bottom")
		(5 "F.SilkS" user "Ref Des/Silkscreen Top")
		(7 "B.SilkS" user "Ref Des/Silkscreen Bottom")
		(1 "F.Mask" user "Board Geometry/Soldermask Top")
		(3 "B.Mask" user "Board Geometry/Soldermask Bottom")
		(17 "Dwgs.User" user "User.Drawings")
		(19 "Cmts.User" user "User.Comments")
		(21 "Eco1.User" user "User.Eco1")
		(23 "Eco2.User" user "User.Eco2")
		(25 "Edge.Cuts" user "Board Geometry/Outline")
		(27 "Margin" user)
		(31 "F.CrtYd" user "Package Geometry/Place Bound Top")
		(29 "B.CrtYd" user "Package Geometry/Place Bound Bottom")
		(35 "F.Fab" user "Ref Des/Assembly Top")
		(33 "B.Fab" user "Ref Des/Assembly Bottom")
	)
	(footprint ""
		(layer "B.Cu")
		(at 473.973906 -19.948398 -90)
		(property "Reference" "R8F3"
			(at 0 0 90)
			(layer "B.SilkS")
			(hide yes)
			(effects
				(font
					(size 1.27 1.27)
				)
				(justify mirror)
			)
		)
		(property "Value" ""
			(at 0 0 90)
			(layer "B.Fab")
			(effects
				(font
					(size 1.27 1.27)
				)
				(justify mirror)
			)
		)
		(duplicate_pad_numbers_are_jumpers no)
		(fp_rect
			(start -0.2794 -0.1016)
			(end 0.2794 0.9906)
			(stroke
				(width 0)
				(type default)
			)
			(fill no)
			(layer "B.CrtYd")
		)
		(fp_line
			(start -0.2794 0.9906)
			(end -0.2794 -0.1016)
			(stroke
				(width 0.1)
				(type default)
			)
			(layer "B.Fab")
		)
		(fp_line
			(start 0.2794 0.9906)
			(end -0.2794 0.9906)
			(stroke
				(width 0.1)
				(type default)
			)
			(layer "B.Fab")
		)
		(fp_line
			(start -0.2794 -0.1016)
			(end 0.2794 -0.1016)
			(stroke
				(width 0.1)
				(type default)
			)
			(layer "B.Fab")
		)
		(fp_line
			(start 0.2794 -0.1016)
			(end 0.2794 0.9906)
			(stroke
				(width 0.1)
				(type default)
			)
			(layer "B.Fab")
		)
		(pad "1" smd rect
			(at 0 0 90)
			(size 0.508 0.508)
			(layers "B.Cu" "B.Mask" "B.Paste")
			(net "VR_P3V3_STBY_SNUB")
		)
		(pad "2" smd rect
			(at 0 0.889 90)
			(size 0.508 0.508)
			(layers "B.Cu" "B.Mask" "B.Paste")
			(net "GND")
		)
		(zone
			(layer "B.Cu")
			(hatch none 0.5)
			(connect_pads
				(clearance 0)
			)
			(min_thickness 0.25)
			(keepout
				(tracks allowed)
				(vias not_allowed)
				(pads allowed)
				(copperpour not_allowed)
				(footprints allowed)
			)
			(placement
				(enabled no)
				(sheetname "")
			)
			(fill
				(thermal_gap 0.5)
				(thermal_bridge_width 0.5)
				(island_removal_mode 0)
			)
			(polygon
				(pts
					(xy 473.719906 -20.202398) (xy 473.338906 -20.202398) (xy 473.338906 -19.694398) (xy 473.719906 -19.694398)
				)
			)
		)
		(zone
			(layer "B.Cu")
			(hatch none 0.5)
			(connect_pads
				(clearance 0)
			)
			(min_thickness 0.25)
			(keepout
				(tracks not_allowed)
				(vias allowed)
				(pads allowed)
				(copperpour not_allowed)
				(footprints allowed)
			)
			(placement
				(enabled no)
				(sheetname "")
			)
			(fill
				(thermal_gap 0.5)
				(thermal_bridge_width 0.5)
				(island_removal_mode 0)
			)
			(polygon
				(pts
					(xy 473.719906 -20.202398) (xy 473.338906 -20.202398) (xy 473.338906 -19.694398) (xy 473.719906 -19.694398)
				)
			)
		)
	)
	(footprint ""
		(layer "B.Cu")
		(at 385.778248 -58.809128 -90)
		(property "Reference" "R2T2"
			(at 0 0 90)
			(layer "B.SilkS")
			(hide yes)
			(effects
				(font
					(size 1.27 1.27)
				)
				(justify mirror)
			)
		)
		(property "Value" ""
			(at 0 0 90)
			(layer "B.Fab")
			(effects
				(font
					(size 1.27 1.27)
				)
				(justify mirror)
			)
		)
		(duplicate_pad_numbers_are_jumpers no)
		(fp_poly
			(pts
				(xy 0.2794 -0.1016) (xy -0.2794 -0.1016) (xy -0.2794 0.9906) (xy 0.2794 0.9906)
			)
			(stroke
				(width 0)
				(type default)
			)
			(fill no)
			(layer "B.CrtYd")
		)
		(fp_line
			(start -0.2794 0.9906)
			(end -0.2794 -0.1016)
			(stroke
				(width 0.1)
				(type default)
			)
			(layer "B.Fab")
		)
		(fp_line
			(start 0.2794 0.9906)
			(end -0.2794 0.9906)
			(stroke
				(width 0.1)
				(type default)
			)
			(layer "B.Fab")
		)
		(fp_line
			(start -0.2794 -0.1016)
			(end 0.2794 -0.1016)
			(stroke
				(width 0.1)
				(type default)
			)
			(layer "B.Fab")
		)
		(fp_line
			(start 0.2794 -0.1016)
			(end 0.2794 0.9906)
			(stroke
				(width 0.1)
				(type default)
			)
			(layer "B.Fab")
		)
		(pad "1" smd rect
			(at 0 0 90)
			(size 0.508 0.508)
			(layers "B.Cu" "B.Mask" "B.Paste")
			(net "SPI_PCH_IO3")
		)
		(pad "2" smd rect
			(at 0 0.889 90)
			(size 0.508 0.508)
			(layers "B.Cu" "B.Mask" "B.Paste")
			(net "SPI_PCH_IO3_R1")
		)
		(zone
			(layer "B.Cu")
			(hatch none 0.5)
			(connect_pads
				(clearance 0)
			)
			(min_thickness 0.25)
			(keepout
				(tracks not_allowed)
				(vias allowed)
				(pads allowed)
				(copperpour not_allowed)
				(footprints allowed)
			)
			(placement
				(enabled no)
				(sheetname "")
			)
			(fill
				(thermal_gap 0.5)
				(thermal_bridge_width 0.5)
				(island_removal_mode 0)
			)
			(polygon
				(pts
					(xy 385.143248 -58.555128) (xy 385.143248 -59.063128) (xy 385.524248 -59.063128) (xy 385.524248 -58.555128)
				)
			)
		)
		(zone
			(layer "B.Cu")
			(hatch none 0.5)
			(connect_pads
				(clearance 0)
			)
			(min_thickness 0.25)
			(keepout
				(tracks allowed)
				(vias not_allowed)
				(pads allowed)
				(copperpour not_allowed)
				(footprints allowed)
			)
			(placement
				(enabled no)
				(sheetname "")
			)
			(fill
				(thermal_gap 0.5)
				(thermal_bridge_width 0.5)
				(island_removal_mode 0)
			)
			(polygon
				(pts
					(xy 385.524248 -58.555128) (xy 385.524248 -59.063128) (xy 385.143248 -59.063128) (xy 385.143248 -58.555128)
				)
			)
		)
	)
	(footprint ""
		(layer "B.Cu")
		(at 378.587 -86.233)
		(property "Reference" "R7C17"
			(at 0.8382 -0.67818 0)
			(unlocked yes)
			(layer "B.SilkS")
			(effects
				(font
					(size 0.4064 0.254)
					(thickness 0.1524)
				)
				(justify left mirror)
			)
		)
		(property "Value" ""
			(at 0 0 0)
			(layer "B.Fab")
			(effects
				(font
					(size 1.27 1.27)
				)
				(justify mirror)
			)
		)
		(duplicate_pad_numbers_are_jumpers no)
		(fp_poly
			(pts
				(xy 0.2794 -0.1016) (xy -0.2794 -0.1016) (xy -0.2794 0.9906) (xy 0.2794 0.9906)
			)
			(stroke
				(width 0)
				(type default)
			)
			(fill no)
			(layer "B.CrtYd")
		)
		(fp_line
			(start -0.2794 -0.1016)
			(end 0.2794 -0.1016)
			(stroke
				(width 0.1)
				(type default)
			)
			(layer "B.Fab")
		)
		(fp_line
			(start -0.2794 0.9906)
			(end -0.2794 -0.1016)
			(stroke
				(width 0.1)
				(type default)
			)
			(layer "B.Fab")
		)
		(fp_line
			(start 0.2794 -0.1016)
			(end 0.2794 0.9906)
			(stroke
				(width 0.1)
				(type default)
			)
			(layer "B.Fab")
		)
		(fp_line
			(start 0.2794 0.9906)
			(end -0.2794 0.9906)
			(stroke
				(width 0.1)
				(type default)
			)
			(layer "B.Fab")
		)
		(pad "1" smd rect
			(at 0 0 180)
			(size 0.508 0.508)
			(layers "B.Cu" "B.Mask" "B.Paste")
			(net "PVCCIO_CPU0")
		)
		(pad "2" smd rect
			(at 0 0.889 180)
			(size 0.508 0.508)
			(layers "B.Cu" "B.Mask" "B.Paste")
			(net "PECI_BMC")
		)
		(zone
			(layer "B.Cu")
			(hatch none 0.5)
			(connect_pads
				(clearance 0)
			)
			(min_thickness 0.25)
			(keepout
				(tracks allowed)
				(vias not_allowed)
				(pads allowed)
				(copperpour not_allowed)
				(footprints allowed)
			)
			(placement
				(enabled no)
				(sheetname "")
			)
			(fill
				(thermal_gap 0.5)
				(thermal_bridge_width 0.5)
				(island_removal_mode 0)
			)
			(polygon
				(pts
					(xy 378.841 -85.979) (xy 378.333 -85.979) (xy 378.333 -85.598) (xy 378.841 -85.598)
				)
			)
		)
		(zone
			(layer "B.Cu")
			(hatch none 0.5)
			(connect_pads
				(clearance 0)
			)
			(min_thickness 0.25)
			(keepout
				(tracks not_allowed)
				(vias allowed)
				(pads allowed)
				(copperpour not_allowed)
				(footprints allowed)
			)
			(placement
				(enabled no)
				(sheetname "")
			)
			(fill
				(thermal_gap 0.5)
				(thermal_bridge_width 0.5)
				(island_removal_mode 0)
			)
			(polygon
				(pts
					(xy 378.841 -85.598) (xy 378.333 -85.598) (xy 378.333 -85.979) (xy 378.841 -85.979)
				)
			)
		)
	)
	(footprint ""
		(layer "B.Cu")
		(at 266.3952 -126.0348 -90)
		(property "Reference" "C5M12"
			(at 0 0 90)
			(layer "B.SilkS")
			(hide yes)
			(effects
				(font
					(size 1.27 1.27)
				)
				(justify mirror)
			)
		)
		(property "Value" ""
			(at 0 0 90)
			(layer "B.Fab")
			(effects
				(font
					(size 1.27 1.27)
				)
				(justify mirror)
			)
		)
		(duplicate_pad_numbers_are_jumpers no)
		(fp_rect
			(start 0.7239 1.9939)
			(end -0.7239 -0.2159)
			(stroke
				(width 0)
				(type default)
			)
			(fill no)
			(layer "B.CrtYd")
		)
		(fp_line
			(start -0.7239 1.9939)
			(end -0.7239 -0.2159)
			(stroke
				(width 0.1)
				(type default)
			)
			(layer "B.Fab")
		)
		(fp_line
			(start 0.7239 1.9939)
			(end -0.7239 1.9939)
			(stroke
				(width 0.1)
				(type default)
			)
			(layer "B.Fab")
		)
		(fp_line
			(start -0.7239 -0.2159)
			(end 0.7239 -0.2159)
			(stroke
				(width 0.1)
				(type default)
			)
			(layer "B.Fab")
		)
		(fp_line
			(start 0.7239 -0.2159)
			(end 0.7239 1.9939)
			(stroke
				(width 0.1)
				(type default)
			)
			(layer "B.Fab")
		)
		(pad "1" smd rect
			(at 0 0 90)
			(size 1.27 1.016)
			(layers "B.Cu" "B.Mask" "B.Paste")
			(net "PVDDQ_DEF")
		)
		(pad "2" smd rect
			(at 0 1.778 90)
			(size 1.27 1.016)
			(layers "B.Cu" "B.Mask" "B.Paste")
			(net "GND")
		)
		(zone
			(layer "B.Cu")
			(hatch none 0.5)
			(connect_pads
				(clearance 0)
			)
			(min_thickness 0.25)
			(keepout
				(tracks not_allowed)
				(vias allowed)
				(pads allowed)
				(copperpour not_allowed)
				(footprints allowed)
			)
			(placement
				(enabled no)
				(sheetname "")
			)
			(fill
				(thermal_gap 0.5)
				(thermal_bridge_width 0.5)
				(island_removal_mode 0)
			)
			(polygon
				(pts
					(xy 265.1252 -125.3998) (xy 265.8872 -125.3998) (xy 265.8872 -126.6698) (xy 265.1252 -126.6698)
				)
			)
		)
	)
	(footprint ""
		(layer "B.Cu")
		(at 494.712244 -49.154588 180)
		(property "Reference" "C25W78"
			(at 0.8382 -0.67818 180)
			(unlocked yes)
			(layer "B.SilkS")
			(effects
				(font
					(size 0.4064 0.254)
					(thickness 0.1524)
				)
				(justify left mirror)
			)
		)
		(property "Value" ""
			(at 0 0 0)
			(layer "B.Fab")
			(effects
				(font
					(size 1.27 1.27)
				)
				(justify mirror)
			)
		)
		(duplicate_pad_numbers_are_jumpers no)
		(fp_poly
			(pts
				(xy -0.3048 -0.1016) (xy -0.3048 0.9906) (xy 0.3048 0.9906) (xy 0.3048 -0.1016)
			)
			(stroke
				(width 0)
				(type default)
			)
			(fill no)
			(layer "B.CrtYd")
		)
		(fp_line
			(start 0.3048 0.9906)
			(end -0.3048 0.9906)
			(stroke
				(width 0.1)
				(type default)
			)
			(layer "B.Fab")
		)
		(fp_line
			(start 0.3048 -0.1016)
			(end 0.3048 0.9906)
			(stroke
				(width 0.1)
				(type default)
			)
			(layer "B.Fab")
		)
		(fp_line
			(start -0.3048 0.9906)
			(end -0.3048 -0.1016)
			(stroke
				(width 0.1)
				(type default)
			)
			(layer "B.Fab")
		)
		(fp_line
			(start -0.3048 -0.1016)
			(end 0.3048 -0.1016)
			(stroke
				(width 0.1)
				(type default)
			)
			(layer "B.Fab")
		)
		(pad "1" smd rect
			(at 0 0)
			(size 0.508 0.508)
			(layers "B.Cu" "B.Mask" "B.Paste")
			(net "V_IBMC_5V_DDC_SCL_J")
		)
		(pad "2" smd rect
			(at 0 0.889)
			(size 0.508 0.508)
			(layers "B.Cu" "B.Mask" "B.Paste")
			(net "GND")
		)
		(zone
			(layer "B.Cu")
			(hatch none 0.5)
			(connect_pads
				(clearance 0)
			)
			(min_thickness 0.25)
			(keepout
				(tracks not_allowed)
				(vias allowed)
				(pads allowed)
				(copperpour not_allowed)
				(footprints allowed)
			)
			(placement
				(enabled no)
				(sheetname "")
			)
			(fill
				(thermal_gap 0.5)
				(thermal_bridge_width 0.5)
				(island_removal_mode 0)
			)
			(polygon
				(pts
					(xy 494.458244 -49.789588) (xy 494.966244 -49.789588) (xy 494.966244 -49.408588) (xy 494.458244 -49.408588)
				)
			)
		)
		(zone
			(layer "B.Cu")
			(hatch none 0.5)
			(connect_pads
				(clearance 0)
			)
			(min_thickness 0.25)
			(keepout
				(tracks allowed)
				(vias not_allowed)
				(pads allowed)
				(copperpour not_allowed)
				(footprints allowed)
			)
			(placement
				(enabled no)
				(sheetname "")
			)
			(fill
				(thermal_gap 0.5)
				(thermal_bridge_width 0.5)
				(island_removal_mode 0)
			)
			(polygon
				(pts
					(xy 494.458244 -49.408588) (xy 494.966244 -49.408588) (xy 494.966244 -49.789588) (xy 494.458244 -49.789588)
				)
			)
		)
	)
	(footprint ""
		(layer "B.Cu")
		(at 395.0843 -20.6248 90)
		(property "Reference" "R32W3"
			(at 0.8382 -0.67818 90)
			(unlocked yes)
			(layer "B.SilkS")
			(effects
				(font
					(size 0.4064 0.254)
					(thickness 0.1524)
				)
				(justify left mirror)
			)
		)
		(property "Value" ""
			(at 0 0 90)
			(layer "B.Fab")
			(effects
				(font
					(size 1.27 1.27)
				)
				(justify mirror)
			)
		)
		(duplicate_pad_numbers_are_jumpers no)
		(fp_poly
			(pts
				(xy 0.2794 -0.1016) (xy -0.2794 -0.1016) (xy -0.2794 0.9906) (xy 0.2794 0.9906)
			)
			(stroke
				(width 0)
				(type default)
			)
			(fill no)
			(layer "B.CrtYd")
		)
		(fp_line
			(start 0.2794 -0.1016)
			(end 0.2794 0.9906)
			(stroke
				(width 0.1)
				(type default)
			)
			(layer "B.Fab")
		)
		(fp_line
			(start -0.2794 -0.1016)
			(end 0.2794 -0.1016)
			(stroke
				(width 0.1)
				(type default)
			)
			(layer "B.Fab")
		)
		(fp_line
			(start 0.2794 0.9906)
			(end -0.2794 0.9906)
			(stroke
				(width 0.1)
				(type default)
			)
			(layer "B.Fab")
		)
		(fp_line
			(start -0.2794 0.9906)
			(end -0.2794 -0.1016)
			(stroke
				(width 0.1)
				(type default)
			)
			(layer "B.Fab")
		)
		(pad "1" smd rect
			(at 0 0 270)
			(size 0.508 0.508)
			(layers "B.Cu" "B.Mask" "B.Paste")
			(net "VREF_LMV431_1V42")
		)
		(pad "2" smd rect
			(at 0 0.889 270)
			(size 0.508 0.508)
			(layers "B.Cu" "B.Mask" "B.Paste")
			(net "GND")
		)
		(zone
			(layer "B.Cu")
			(hatch none 0.5)
			(connect_pads
				(clearance 0)
			)
			(min_thickness 0.25)
			(keepout
				(tracks allowed)
				(vias not_allowed)
				(pads allowed)
				(copperpour not_allowed)
				(footprints allowed)
			)
			(placement
				(enabled no)
				(sheetname "")
			)
			(fill
				(thermal_gap 0.5)
				(thermal_bridge_width 0.5)
				(island_removal_mode 0)
			)
			(polygon
				(pts
					(xy 395.3383 -20.8788) (xy 395.3383 -20.3708) (xy 395.7193 -20.3708) (xy 395.7193 -20.8788)
				)
			)
		)
		(zone
			(layer "B.Cu")
			(hatch none 0.5)
			(connect_pads
				(clearance 0)
			)
			(min_thickness 0.25)
			(keepout
				(tracks not_allowed)
				(vias allowed)
				(pads allowed)
				(copperpour not_allowed)
				(footprints allowed)
			)
			(placement
				(enabled no)
				(sheetname "")
			)
			(fill
				(thermal_gap 0.5)
				(thermal_bridge_width 0.5)
				(island_removal_mode 0)
			)
			(polygon
				(pts
					(xy 395.7193 -20.8788) (xy 395.7193 -20.3708) (xy 395.3383 -20.3708) (xy 395.3383 -20.8788)
				)
			)
		)
	)
	(footprint ""
		(layer "B.Cu")
		(at 394.337032 -66.273172 90)
		(property "Reference" "R2T13"
			(at 0 0 90)
			(layer "B.SilkS")
			(hide yes)
			(effects
				(font
					(size 1.27 1.27)
				)
				(justify mirror)
			)
		)
		(property "Value" ""
			(at 0 0 90)
			(layer "B.Fab")
			(effects
				(font
					(size 1.27 1.27)
				)
				(justify mirror)
			)
		)
		(duplicate_pad_numbers_are_jumpers no)
		(fp_poly
			(pts
				(xy 0.2794 -0.1016) (xy -0.2794 -0.1016) (xy -0.2794 0.9906) (xy 0.2794 0.9906)
			)
			(stroke
				(width 0)
				(type default)
			)
			(fill no)
			(layer "B.CrtYd")
		)
		(fp_line
			(start 0.2794 -0.1016)
			(end 0.2794 0.9906)
			(stroke
				(width 0.1)
				(type default)
			)
			(layer "B.Fab")
		)
		(fp_line
			(start -0.2794 -0.1016)
			(end 0.2794 -0.1016)
			(stroke
				(width 0.1)
				(type default)
			)
			(layer "B.Fab")
		)
		(fp_line
			(start 0.2794 0.9906)
			(end -0.2794 0.9906)
			(stroke
				(width 0.1)
				(type default)
			)
			(layer "B.Fab")
		)
		(fp_line
			(start -0.2794 0.9906)
			(end -0.2794 -0.1016)
			(stroke
				(width 0.1)
				(type default)
			)
			(layer "B.Fab")
		)
		(pad "1" smd rect
			(at 0 0 270)
			(size 0.508 0.508)
			(layers "B.Cu" "B.Mask" "B.Paste")
			(net "SPI_CS0_PRIMARY_N")
		)
		(pad "2" smd rect
			(at 0 0.889 270)
			(size 0.508 0.508)
			(layers "B.Cu" "B.Mask" "B.Paste")
			(net "SPI_CS0_PRIMARY_R_N")
		)
		(zone
			(layer "B.Cu")
			(hatch none 0.5)
			(connect_pads
				(clearance 0)
			)
			(min_thickness 0.25)
			(keepout
				(tracks allowed)
				(vias not_allowed)
				(pads allowed)
				(copperpour not_allowed)
				(footprints allowed)
			)
			(placement
				(enabled no)
				(sheetname "")
			)
			(fill
				(thermal_gap 0.5)
				(thermal_bridge_width 0.5)
				(island_removal_mode 0)
			)
			(polygon
				(pts
					(xy 394.591032 -66.527172) (xy 394.591032 -66.019172) (xy 394.972032 -66.019172) (xy 394.972032 -66.527172)
				)
			)
		)
		(zone
			(layer "B.Cu")
			(hatch none 0.5)
			(connect_pads
				(clearance 0)
			)
			(min_thickness 0.25)
			(keepout
				(tracks not_allowed)
				(vias allowed)
				(pads allowed)
				(copperpour not_allowed)
				(footprints allowed)
			)
			(placement
				(enabled no)
				(sheetname "")
			)
			(fill
				(thermal_gap 0.5)
				(thermal_bridge_width 0.5)
				(island_removal_mode 0)
			)
			(polygon
				(pts
					(xy 394.972032 -66.527172) (xy 394.972032 -66.019172) (xy 394.591032 -66.019172) (xy 394.591032 -66.527172)
				)
			)
		)
	)
)
